(kicad_pcb
	(version 20260206)
	(generator "pcbnew")
	(generator_version "10.0")
	(general
		(thickness 1.6)
		(legacy_teardrops no)
	)
	(paper "A4")
	(title_block
		(title "01162023_DA0F0TEBIF0_F0T_Expander_BD_F_brd_V02_OCP.brd")
		(comment 1 "Grand Teton / footprints 6009-6014 of 9728")
	)
	(layers
		(0 "F.Cu" signal "TOP")
		(4 "In1.Cu" signal "GND")
		(6 "In2.Cu" signal "VCC")
		(8 "In3.Cu" signal "VCC1")
		(10 "In4.Cu" signal "GND1")
		(12 "In5.Cu" signal "IN1")
		(14 "In6.Cu" signal "GND2")
		(16 "In7.Cu" signal "IN2")
		(18 "In8.Cu" signal "GND3")
		(20 "In9.Cu" signal "IN3")
		(22 "In10.Cu" signal "GND4")
		(24 "In11.Cu" signal "IN4")
		(26 "In12.Cu" signal "GND5")
		(28 "In13.Cu" signal "IN5")
		(30 "In14.Cu" signal "GND6")
		(32 "In15.Cu" signal "IN6")
		(34 "In16.Cu" signal "GND7")
		(2 "B.Cu" signal "BOTTOM")
		(9 "F.Adhes" user "F.Adhesive")
		(11 "B.Adhes" user "B.Adhesive")
		(13 "F.Paste" user "Package Geometry/Pastemask Top")
		(15 "B.Paste" user "Package Geometry/Pastemask Bottom")
		(5 "F.SilkS" user "Ref Des/Silkscreen Top")
		(7 "B.SilkS" user "Ref Des/Silkscreen Bottom")
		(1 "F.Mask" user "Board Geometry/Soldermask Top")
		(3 "B.Mask" user "Board Geometry/Soldermask Bottom")
		(17 "Dwgs.User" user "User.Drawings")
		(19 "Cmts.User" user "User.Comments")
		(21 "Eco1.User" user "User.Eco1")
		(23 "Eco2.User" user "User.Eco2")
		(25 "Edge.Cuts" user "Board Geometry/Outline")
		(27 "Margin" user)
		(31 "F.CrtYd" user "Package Geometry/Place Bound Top")
		(29 "B.CrtYd" user "Package Geometry/Place Bound Bottom")
		(35 "F.Fab" user "Ref Des/Assembly Top")
		(33 "B.Fab" user "Ref Des/Assembly Bottom")
	)
	(footprint ""
		(layer "F.Cu")
		(at 290.775644 -36.915598 -90)
		(property "Reference" "R5577"
			(at 0 0 270)
			(layer "F.SilkS")
			(hide yes)
			(effects
				(font
					(size 1.27 1.27)
				)
			)
		)
		(property "Value" ""
			(at 0 0 270)
			(layer "F.Fab")
			(effects
				(font
					(size 1.27 1.27)
				)
			)
		)
		(duplicate_pad_numbers_are_jumpers no)
		(fp_line
			(start -0.7874 0.4064)
			(end -0.7874 -0.4064)
			(stroke
				(width 0.1524)
				(type default)
			)
			(layer "F.SilkS")
		)
		(fp_line
			(start 0.7874 0.4064)
			(end -0.7874 0.4064)
			(stroke
				(width 0.1524)
				(type default)
			)
			(layer "F.SilkS")
		)
		(fp_line
			(start -0.7874 -0.4064)
			(end 0.7874 -0.4064)
			(stroke
				(width 0.1524)
				(type default)
			)
			(layer "F.SilkS")
		)
		(fp_line
			(start 0.7874 -0.4064)
			(end 0.7874 0.4064)
			(stroke
				(width 0.1524)
				(type default)
			)
			(layer "F.SilkS")
		)
		(fp_line
			(start -0.67945 0.3048)
			(end -0.67945 -0.305054)
			(stroke
				(width 0.1)
				(type default)
			)
			(layer "F.Fab")
		)
		(fp_line
			(start -0.12065 0.3048)
			(end -0.67945 0.3048)
			(stroke
				(width 0.1)
				(type default)
			)
			(layer "F.Fab")
		)
		(fp_line
			(start 0.120396 0.3048)
			(end 0.120396 0.2794)
			(stroke
				(width 0.1)
				(type default)
			)
			(layer "F.Fab")
		)
		(fp_line
			(start 0.67945 0.3048)
			(end 0.120396 0.3048)
			(stroke
				(width 0.1)
				(type default)
			)
			(layer "F.Fab")
		)
		(fp_line
			(start -0.12065 0.2794)
			(end -0.12065 0.3048)
			(stroke
				(width 0.1)
				(type default)
			)
			(layer "F.Fab")
		)
		(fp_line
			(start 0.120396 0.2794)
			(end -0.12065 0.2794)
			(stroke
				(width 0.1)
				(type default)
			)
			(layer "F.Fab")
		)
		(fp_line
			(start -0.12065 -0.2794)
			(end 0.12065 -0.2794)
			(stroke
				(width 0.1)
				(type default)
			)
			(layer "F.Fab")
		)
		(fp_line
			(start 0.12065 -0.2794)
			(end 0.12065 -0.3048)
			(stroke
				(width 0.1)
				(type default)
			)
			(layer "F.Fab")
		)
		(fp_line
			(start 0.12065 -0.3048)
			(end 0.67945 -0.3048)
			(stroke
				(width 0.1)
				(type default)
			)
			(layer "F.Fab")
		)
		(fp_line
			(start 0.67945 -0.3048)
			(end 0.67945 0.3048)
			(stroke
				(width 0.1)
				(type default)
			)
			(layer "F.Fab")
		)
		(fp_line
			(start -0.67945 -0.305054)
			(end -0.12065 -0.305054)
			(stroke
				(width 0.1)
				(type default)
			)
			(layer "F.Fab")
		)
		(fp_line
			(start -0.12065 -0.305054)
			(end -0.12065 -0.2794)
			(stroke
				(width 0.1)
				(type default)
			)
			(layer "F.Fab")
		)
		(pad "1" smd circle
			(at -0.40005 0 270)
			(size 0 0)
			(layers "F.Cu" "F.Mask" "F.Paste")
			(net "PRSNT_SSD10_R1_N")
		)
		(pad "2" smd circle
			(at 0.40005 0 270)
			(size 0 0)
			(layers "F.Cu" "F.Mask" "F.Paste")
			(net "PRSNT_SSD10_R_N")
		)
	)
	(footprint ""
		(layer "F.Cu")
		(at 332.085442 -27.092148 -90)
		(property "Reference" "R5757"
			(at 0 0 270)
			(layer "F.SilkS")
			(hide yes)
			(effects
				(font
					(size 1.27 1.27)
				)
			)
		)
		(property "Value" ""
			(at 0 0 270)
			(layer "F.Fab")
			(effects
				(font
					(size 1.27 1.27)
				)
			)
		)
		(duplicate_pad_numbers_are_jumpers no)
		(fp_line
			(start -0.7874 0.4064)
			(end -0.7874 -0.4064)
			(stroke
				(width 0.1524)
				(type default)
			)
			(layer "F.SilkS")
		)
		(fp_line
			(start 0.7874 0.4064)
			(end -0.7874 0.4064)
			(stroke
				(width 0.1524)
				(type default)
			)
			(layer "F.SilkS")
		)
		(fp_line
			(start -0.7874 -0.4064)
			(end 0.7874 -0.4064)
			(stroke
				(width 0.1524)
				(type default)
			)
			(layer "F.SilkS")
		)
		(fp_line
			(start 0.7874 -0.4064)
			(end 0.7874 0.4064)
			(stroke
				(width 0.1524)
				(type default)
			)
			(layer "F.SilkS")
		)
		(fp_line
			(start -0.67945 0.3048)
			(end -0.67945 -0.305054)
			(stroke
				(width 0.1)
				(type default)
			)
			(layer "F.Fab")
		)
		(fp_line
			(start -0.12065 0.3048)
			(end -0.67945 0.3048)
			(stroke
				(width 0.1)
				(type default)
			)
			(layer "F.Fab")
		)
		(fp_line
			(start 0.120396 0.3048)
			(end 0.120396 0.2794)
			(stroke
				(width 0.1)
				(type default)
			)
			(layer "F.Fab")
		)
		(fp_line
			(start 0.67945 0.3048)
			(end 0.120396 0.3048)
			(stroke
				(width 0.1)
				(type default)
			)
			(layer "F.Fab")
		)
		(fp_line
			(start -0.12065 0.2794)
			(end -0.12065 0.3048)
			(stroke
				(width 0.1)
				(type default)
			)
			(layer "F.Fab")
		)
		(fp_line
			(start 0.120396 0.2794)
			(end -0.12065 0.2794)
			(stroke
				(width 0.1)
				(type default)
			)
			(layer "F.Fab")
		)
		(fp_line
			(start -0.12065 -0.2794)
			(end 0.12065 -0.2794)
			(stroke
				(width 0.1)
				(type default)
			)
			(layer "F.Fab")
		)
		(fp_line
			(start 0.12065 -0.2794)
			(end 0.12065 -0.3048)
			(stroke
				(width 0.1)
				(type default)
			)
			(layer "F.Fab")
		)
		(fp_line
			(start 0.12065 -0.3048)
			(end 0.67945 -0.3048)
			(stroke
				(width 0.1)
				(type default)
			)
			(layer "F.Fab")
		)
		(fp_line
			(start 0.67945 -0.3048)
			(end 0.67945 0.3048)
			(stroke
				(width 0.1)
				(type default)
			)
			(layer "F.Fab")
		)
		(fp_line
			(start -0.67945 -0.305054)
			(end -0.12065 -0.305054)
			(stroke
				(width 0.1)
				(type default)
			)
			(layer "F.Fab")
		)
		(fp_line
			(start -0.12065 -0.305054)
			(end -0.12065 -0.2794)
			(stroke
				(width 0.1)
				(type default)
			)
			(layer "F.Fab")
		)
		(pad "1" smd circle
			(at -0.40005 0 270)
			(size 0 0)
			(layers "F.Cu" "F.Mask" "F.Paste")
			(net "P3V3_SSD11")
		)
		(pad "2" smd circle
			(at 0.40005 0 270)
			(size 0 0)
			(layers "F.Cu" "F.Mask" "F.Paste")
			(net "SSD11_LED_ISO_N")
		)
	)
	(footprint ""
		(layer "F.Cu")
		(at 447.275712 -120.493028)
		(property "Reference" "R4481"
			(at 0 0 0)
			(layer "F.SilkS")
			(hide yes)
			(effects
				(font
					(size 1.27 1.27)
				)
			)
		)
		(property "Value" ""
			(at 0 0 0)
			(layer "F.Fab")
			(effects
				(font
					(size 1.27 1.27)
				)
			)
		)
		(duplicate_pad_numbers_are_jumpers no)
		(fp_line
			(start -0.7874 -0.4064)
			(end 0.7874 -0.4064)
			(stroke
				(width 0.1524)
				(type default)
			)
			(layer "F.SilkS")
		)
		(fp_line
			(start -0.7874 0.4064)
			(end -0.7874 -0.4064)
			(stroke
				(width 0.1524)
				(type default)
			)
			(layer "F.SilkS")
		)
		(fp_line
			(start 0.7874 -0.4064)
			(end 0.7874 0.4064)
			(stroke
				(width 0.1524)
				(type default)
			)
			(layer "F.SilkS")
		)
		(fp_line
			(start 0.7874 0.4064)
			(end -0.7874 0.4064)
			(stroke
				(width 0.1524)
				(type default)
			)
			(layer "F.SilkS")
		)
		(fp_line
			(start -0.67945 -0.305054)
			(end -0.12065 -0.305054)
			(stroke
				(width 0.1)
				(type default)
			)
			(layer "F.Fab")
		)
		(fp_line
			(start -0.67945 0.3048)
			(end -0.67945 -0.305054)
			(stroke
				(width 0.1)
				(type default)
			)
			(layer "F.Fab")
		)
		(fp_line
			(start -0.12065 -0.305054)
			(end -0.12065 -0.2794)
			(stroke
				(width 0.1)
				(type default)
			)
			(layer "F.Fab")
		)
		(fp_line
			(start -0.12065 -0.2794)
			(end 0.12065 -0.2794)
			(stroke
				(width 0.1)
				(type default)
			)
			(layer "F.Fab")
		)
		(fp_line
			(start -0.12065 0.2794)
			(end -0.12065 0.3048)
			(stroke
				(width 0.1)
				(type default)
			)
			(layer "F.Fab")
		)
		(fp_line
			(start -0.12065 0.3048)
			(end -0.67945 0.3048)
			(stroke
				(width 0.1)
				(type default)
			)
			(layer "F.Fab")
		)
		(fp_line
			(start 0.120396 0.2794)
			(end -0.12065 0.2794)
			(stroke
				(width 0.1)
				(type default)
			)
			(layer "F.Fab")
		)
		(fp_line
			(start 0.120396 0.3048)
			(end 0.120396 0.2794)
			(stroke
				(width 0.1)
				(type default)
			)
			(layer "F.Fab")
		)
		(fp_line
			(start 0.12065 -0.3048)
			(end 0.67945 -0.3048)
			(stroke
				(width 0.1)
				(type default)
			)
			(layer "F.Fab")
		)
		(fp_line
			(start 0.12065 -0.2794)
			(end 0.12065 -0.3048)
			(stroke
				(width 0.1)
				(type default)
			)
			(layer "F.Fab")
		)
		(fp_line
			(start 0.67945 -0.3048)
			(end 0.67945 0.3048)
			(stroke
				(width 0.1)
				(type default)
			)
			(layer "F.Fab")
		)
		(fp_line
			(start 0.67945 0.3048)
			(end 0.120396 0.3048)
			(stroke
				(width 0.1)
				(type default)
			)
			(layer "F.Fab")
		)
		(pad "1" smd circle
			(at -0.40005 0)
			(size 0 0)
			(layers "F.Cu" "F.Mask" "F.Paste")
			(net "PWRGD_P3V3_NIC7")
		)
		(pad "2" smd circle
			(at 0.40005 0)
			(size 0 0)
			(layers "F.Cu" "F.Mask" "F.Paste")
			(net "PWRGD_P3V3_NIC7_R")
		)
	)
	(footprint ""
		(layer "F.Cu")
		(at 242.310412 -126.995428 180)
		(property "Reference" "PC459"
			(at 0 0 180)
			(layer "F.SilkS")
			(hide yes)
			(effects
				(font
					(size 1.27 1.27)
				)
			)
		)
		(property "Value" ""
			(at 0 0 180)
			(layer "F.Fab")
			(effects
				(font
					(size 1.27 1.27)
				)
			)
		)
		(duplicate_pad_numbers_are_jumpers no)
		(fp_line
			(start 0.7874 0.4064)
			(end -0.7874 0.4064)
			(stroke
				(width 0.1524)
				(type default)
			)
			(layer "F.SilkS")
		)
		(fp_line
			(start 0.7874 -0.4064)
			(end 0.7874 0.4064)
			(stroke
				(width 0.1524)
				(type default)
			)
			(layer "F.SilkS")
		)
		(fp_line
			(start -0.7874 0.4064)
			(end -0.7874 -0.4064)
			(stroke
				(width 0.1524)
				(type default)
			)
			(layer "F.SilkS")
		)
		(fp_line
			(start -0.7874 -0.4064)
			(end 0.7874 -0.4064)
			(stroke
				(width 0.1524)
				(type default)
			)
			(layer "F.SilkS")
		)
		(fp_line
			(start 0.67945 0.3048)
			(end 0.120396 0.3048)
			(stroke
				(width 0.1)
				(type default)
			)
			(layer "F.Fab")
		)
		(fp_line
			(start 0.67945 -0.3048)
			(end 0.67945 0.3048)
			(stroke
				(width 0.1)
				(type default)
			)
			(layer "F.Fab")
		)
		(fp_line
			(start 0.12065 -0.2794)
			(end 0.12065 -0.3048)
			(stroke
				(width 0.1)
				(type default)
			)
			(layer "F.Fab")
		)
		(fp_line
			(start 0.12065 -0.3048)
			(end 0.67945 -0.3048)
			(stroke
				(width 0.1)
				(type default)
			)
			(layer "F.Fab")
		)
		(fp_line
			(start 0.120396 0.3048)
			(end 0.120396 0.2794)
			(stroke
				(width 0.1)
				(type default)
			)
			(layer "F.Fab")
		)
		(fp_line
			(start 0.120396 0.2794)
			(end -0.12065 0.2794)
			(stroke
				(width 0.1)
				(type default)
			)
			(layer "F.Fab")
		)
		(fp_line
			(start -0.12065 0.3048)
			(end -0.67945 0.3048)
			(stroke
				(width 0.1)
				(type default)
			)
			(layer "F.Fab")
		)
		(fp_line
			(start -0.12065 0.2794)
			(end -0.12065 0.3048)
			(stroke
				(width 0.1)
				(type default)
			)
			(layer "F.Fab")
		)
		(fp_line
			(start -0.12065 -0.2794)
			(end 0.12065 -0.2794)
			(stroke
				(width 0.1)
				(type default)
			)
			(layer "F.Fab")
		)
		(fp_line
			(start -0.12065 -0.305054)
			(end -0.12065 -0.2794)
			(stroke
				(width 0.1)
				(type default)
			)
			(layer "F.Fab")
		)
		(fp_line
			(start -0.67945 0.3048)
			(end -0.67945 -0.305054)
			(stroke
				(width 0.1)
				(type default)
			)
			(layer "F.Fab")
		)
		(fp_line
			(start -0.67945 -0.305054)
			(end -0.12065 -0.305054)
			(stroke
				(width 0.1)
				(type default)
			)
			(layer "F.Fab")
		)
		(pad "1" smd circle
			(at -0.40005 0 180)
			(size 0 0)
			(layers "F.Cu" "F.Mask" "F.Paste")
			(net "P3V3_NIC4_SS")
		)
		(pad "2" smd circle
			(at 0.40005 0 180)
			(size 0 0)
			(layers "F.Cu" "F.Mask" "F.Paste")
			(net "GND")
		)
	)
	(footprint ""
		(layer "F.Cu")
		(at 403.175216 -63.086234)
		(property "Reference" "R6028"
			(at 0 0 0)
			(layer "F.SilkS")
			(hide yes)
			(effects
				(font
					(size 1.27 1.27)
				)
			)
		)
		(property "Value" ""
			(at 0 0 0)
			(layer "F.Fab")
			(effects
				(font
					(size 1.27 1.27)
				)
			)
		)
		(duplicate_pad_numbers_are_jumpers no)
		(fp_line
			(start -0.7874 -0.4064)
			(end 0.7874 -0.4064)
			(stroke
				(width 0.1524)
				(type default)
			)
			(layer "F.SilkS")
		)
		(fp_line
			(start -0.7874 0.4064)
			(end -0.7874 -0.4064)
			(stroke
				(width 0.1524)
				(type default)
			)
			(layer "F.SilkS")
		)
		(fp_line
			(start 0.7874 -0.4064)
			(end 0.7874 0.4064)
			(stroke
				(width 0.1524)
				(type default)
			)
			(layer "F.SilkS")
		)
		(fp_line
			(start 0.7874 0.4064)
			(end -0.7874 0.4064)
			(stroke
				(width 0.1524)
				(type default)
			)
			(layer "F.SilkS")
		)
		(fp_line
			(start -0.67945 -0.305054)
			(end -0.12065 -0.305054)
			(stroke
				(width 0.1)
				(type default)
			)
			(layer "F.Fab")
		)
		(fp_line
			(start -0.67945 0.3048)
			(end -0.67945 -0.305054)
			(stroke
				(width 0.1)
				(type default)
			)
			(layer "F.Fab")
		)
		(fp_line
			(start -0.12065 -0.305054)
			(end -0.12065 -0.2794)
			(stroke
				(width 0.1)
				(type default)
			)
			(layer "F.Fab")
		)
		(fp_line
			(start -0.12065 -0.2794)
			(end 0.12065 -0.2794)
			(stroke
				(width 0.1)
				(type default)
			)
			(layer "F.Fab")
		)
		(fp_line
			(start -0.12065 0.2794)
			(end -0.12065 0.3048)
			(stroke
				(width 0.1)
				(type default)
			)
			(layer "F.Fab")
		)
		(fp_line
			(start -0.12065 0.3048)
			(end -0.67945 0.3048)
			(stroke
				(width 0.1)
				(type default)
			)
			(layer "F.Fab")
		)
		(fp_line
			(start 0.120396 0.2794)
			(end -0.12065 0.2794)
			(stroke
				(width 0.1)
				(type default)
			)
			(layer "F.Fab")
		)
		(fp_line
			(start 0.120396 0.3048)
			(end 0.120396 0.2794)
			(stroke
				(width 0.1)
				(type default)
			)
			(layer "F.Fab")
		)
		(fp_line
			(start 0.12065 -0.3048)
			(end 0.67945 -0.3048)
			(stroke
				(width 0.1)
				(type default)
			)
			(layer "F.Fab")
		)
		(fp_line
			(start 0.12065 -0.2794)
			(end 0.12065 -0.3048)
			(stroke
				(width 0.1)
				(type default)
			)
			(layer "F.Fab")
		)
		(fp_line
			(start 0.67945 -0.3048)
			(end 0.67945 0.3048)
			(stroke
				(width 0.1)
				(type default)
			)
			(layer "F.Fab")
		)
		(fp_line
			(start 0.67945 0.3048)
			(end 0.120396 0.3048)
			(stroke
				(width 0.1)
				(type default)
			)
			(layer "F.Fab")
		)
		(pad "1" smd circle
			(at -0.40005 0)
			(size 0 0)
			(layers "F.Cu" "F.Mask" "F.Paste")
			(net "P12V_SSD14_R")
		)
		(pad "2" smd circle
			(at 0.40005 0)
			(size 0 0)
			(layers "F.Cu" "F.Mask" "F.Paste")
			(net "P12V_SSD14_PG_G1")
		)
	)
	(footprint ""
		(layer "F.Cu")
		(at 359.156 -175.006 180)
		(property "Reference" "R4677"
			(at 0 0 180)
			(layer "F.SilkS")
			(hide yes)
			(effects
				(font
					(size 1.27 1.27)
				)
			)
		)
		(property "Value" ""
			(at 0 0 180)
			(layer "F.Fab")
			(effects
				(font
					(size 1.27 1.27)
				)
			)
		)
		(duplicate_pad_numbers_are_jumpers no)
		(fp_line
			(start 0.7874 0.4064)
			(end -0.7874 0.4064)
			(stroke
				(width 0.1524)
				(type default)
			)
			(layer "F.SilkS")
		)
		(fp_line
			(start 0.7874 -0.4064)
			(end 0.7874 0.4064)
			(stroke
				(width 0.1524)
				(type default)
			)
			(layer "F.SilkS")
		)
		(fp_line
			(start -0.7874 0.4064)
			(end -0.7874 -0.4064)
			(stroke
				(width 0.1524)
				(type default)
			)
			(layer "F.SilkS")
		)
		(fp_line
			(start -0.7874 -0.4064)
			(end 0.7874 -0.4064)
			(stroke
				(width 0.1524)
				(type default)
			)
			(layer "F.SilkS")
		)
		(fp_line
			(start 0.67945 0.3048)
			(end 0.120396 0.3048)
			(stroke
				(width 0.1)
				(type default)
			)
			(layer "F.Fab")
		)
		(fp_line
			(start 0.67945 -0.3048)
			(end 0.67945 0.3048)
			(stroke
				(width 0.1)
				(type default)
			)
			(layer "F.Fab")
		)
		(fp_line
			(start 0.12065 -0.2794)
			(end 0.12065 -0.3048)
			(stroke
				(width 0.1)
				(type default)
			)
			(layer "F.Fab")
		)
		(fp_line
			(start 0.12065 -0.3048)
			(end 0.67945 -0.3048)
			(stroke
				(width 0.1)
				(type default)
			)
			(layer "F.Fab")
		)
		(fp_line
			(start 0.120396 0.3048)
			(end 0.120396 0.2794)
			(stroke
				(width 0.1)
				(type default)
			)
			(layer "F.Fab")
		)
		(fp_line
			(start 0.120396 0.2794)
			(end -0.12065 0.2794)
			(stroke
				(width 0.1)
				(type default)
			)
			(layer "F.Fab")
		)
		(fp_line
			(start -0.12065 0.3048)
			(end -0.67945 0.3048)
			(stroke
				(width 0.1)
				(type default)
			)
			(layer "F.Fab")
		)
		(fp_line
			(start -0.12065 0.2794)
			(end -0.12065 0.3048)
			(stroke
				(width 0.1)
				(type default)
			)
			(layer "F.Fab")
		)
		(fp_line
			(start -0.12065 -0.2794)
			(end 0.12065 -0.2794)
			(stroke
				(width 0.1)
				(type default)
			)
			(layer "F.Fab")
		)
		(fp_line
			(start -0.12065 -0.305054)
			(end -0.12065 -0.2794)
			(stroke
				(width 0.1)
				(type default)
			)
			(layer "F.Fab")
		)
		(fp_line
			(start -0.67945 0.3048)
			(end -0.67945 -0.305054)
			(stroke
				(width 0.1)
				(type default)
			)
			(layer "F.Fab")
		)
		(fp_line
			(start -0.67945 -0.305054)
			(end -0.12065 -0.305054)
			(stroke
				(width 0.1)
				(type default)
			)
			(layer "F.Fab")
		)
		(pad "1" smd circle
			(at -0.40005 0 180)
			(size 0 0)
			(layers "F.Cu" "F.Mask" "F.Paste")
			(net "SSD7_PEX_PWR_EN_R")
		)
		(pad "2" smd circle
			(at 0.40005 0 180)
			(size 0 0)
			(layers "F.Cu" "F.Mask" "F.Paste")
			(net "GND")
		)
	)
)
